(kicad_pcb
	(version 20260206)
	(generator "pcbnew")
	(generator_version "10.0")
	(general
		(thickness 1.6)
		(legacy_teardrops no)
	)
	(paper "A4")
	(title_block
		(title "baseboard — 13948-1b.1110WZS1818.brd")
		(comment 1 "Honey Badger (Wiwynn) / footprints 751-758 of 2523")
	)
	(layers
		(0 "F.Cu" signal "TOP")
		(4 "In1.Cu" signal "L2GND")
		(6 "In2.Cu" signal "L3")
		(8 "In3.Cu" signal "L4VCC")
		(10 "In4.Cu" signal "L5VCC")
		(12 "In5.Cu" signal "L6")
		(14 "In6.Cu" signal "L7GND")
		(2 "B.Cu" signal "BOTTOM")
		(9 "F.Adhes" user "F.Adhesive")
		(11 "B.Adhes" user "B.Adhesive")
		(13 "F.Paste" user "Package Geometry/Pastemask Top")
		(15 "B.Paste" user "Package Geometry/Pastemask Bottom")
		(5 "F.SilkS" user "Ref Des/Silkscreen Top")
		(7 "B.SilkS" user "Ref Des/Silkscreen Bottom")
		(1 "F.Mask" user "Board Geometry/Soldermask Top")
		(3 "B.Mask" user "Board Geometry/Soldermask Bottom")
		(17 "Dwgs.User" user "User.Drawings")
		(19 "Cmts.User" user "User.Comments")
		(21 "Eco1.User" user "User.Eco1")
		(23 "Eco2.User" user "User.Eco2")
		(25 "Edge.Cuts" user "Board Geometry/Outline")
		(27 "Margin" user)
		(31 "F.CrtYd" user "Package Geometry/Place Bound Top")
		(29 "B.CrtYd" user "Package Geometry/Place Bound Bottom")
		(35 "F.Fab" user "Ref Des/Assembly Top")
		(33 "B.Fab" user "Ref Des/Assembly Bottom")
	)
	(footprint ""
		(layer "F.Cu")
		(at 274.193 -173.609 90)
		(property "Reference" "R368"
			(at 0 0 90)
			(layer "F.SilkS")
			(hide yes)
			(effects
				(font
					(size 1.27 1.27)
				)
			)
		)
		(property "Value" "3K3R2F-2-GP"
			(at 0.064008 -3.993896 90)
			(unlocked yes)
			(layer "F.Fab")
			(hide yes)
			(effects
				(font
					(size 1.016 1.016)
					(thickness 0.1524)
				)
			)
		)
		(property "Device Type" "R402H16"
			(at 0.064008 -5.517896 90)
			(unlocked yes)
			(layer "F.Fab")
			(hide yes)
			(effects
				(font
					(size 1.016 1.016)
					(thickness 0.1524)
				)
			)
		)
		(duplicate_pad_numbers_are_jumpers no)
		(fp_line
			(start 0.508 -0.9398)
			(end -0.508 -0.9398)
			(stroke
				(width 0.1524)
				(type default)
			)
			(layer "F.SilkS")
		)
		(fp_line
			(start -0.508 -0.9398)
			(end -0.508 0.9398)
			(stroke
				(width 0.1524)
				(type default)
			)
			(layer "F.SilkS")
		)
		(fp_rect
			(start -0.508 0.9398)
			(end 0.508 -0.9398)
			(stroke
				(width 0)
				(type default)
			)
			(fill no)
			(layer "F.CrtYd")
		)
		(fp_rect
			(start -0.508 0.9398)
			(end 0.508 -0.9398)
			(stroke
				(width 0)
				(type default)
			)
			(fill no)
			(layer "F.Fab")
		)
		(pad "1" smd custom
			(at 0 -0.4445 90)
			(size 0.1397 0.1397)
			(layers "F.Cu" "F.Mask" "F.Paste")
			(net "P3V3_STBY")
			(options
				(clearance outline)
				(anchor circle)
			)
			(primitives
				(gr_poly
					(pts
						(arc
							(start -0.1778 -0.2794)
							(mid -0.249642 -0.249642)
							(end -0.2794 -0.1778)
						)
						(arc
							(start -0.2794 0.1778)
							(mid -0.249642 0.249642)
							(end -0.1778 0.2794)
						)
						(arc
							(start 0.1778 0.2794)
							(mid 0.249642 0.249642)
							(end 0.2794 0.1778)
						)
						(arc
							(start 0.2794 -0.1778)
							(mid 0.249642 -0.249642)
							(end 0.1778 -0.2794)
						)
					)
					(width 0)
					(fill yes)
				)
			)
		)
		(pad "2" smd custom
			(at 0 0.4445 90)
			(size 0.1397 0.1397)
			(layers "F.Cu" "F.Mask" "F.Paste")
			(net "ROMA15")
			(options
				(clearance outline)
				(anchor circle)
			)
			(primitives
				(gr_poly
					(pts
						(arc
							(start -0.1778 -0.2794)
							(mid -0.249642 -0.249642)
							(end -0.2794 -0.1778)
						)
						(arc
							(start -0.2794 0.1778)
							(mid -0.249642 0.249642)
							(end -0.1778 0.2794)
						)
						(arc
							(start 0.1778 0.2794)
							(mid 0.249642 0.249642)
							(end 0.2794 0.1778)
						)
						(arc
							(start 0.2794 -0.1778)
							(mid 0.249642 -0.249642)
							(end 0.1778 -0.2794)
						)
					)
					(width 0)
					(fill yes)
				)
			)
		)
	)
	(footprint ""
		(layer "F.Cu")
		(at 94.996 -99.695)
		(property "Reference" "STP87"
			(at 0 0 0)
			(layer "F.SilkS")
			(hide yes)
			(effects
				(font
					(size 1.27 1.27)
				)
			)
		)
		(property "Value" "TPAD28"
			(at 0.0127 -1.8034 0)
			(unlocked yes)
			(layer "F.Fab")
			(hide yes)
			(effects
				(font
					(size 1.016 1.016)
					(thickness 0.1524)
				)
			)
		)
		(property "Device Type" "TPAD28"
			(at 0.0127 -3.3274 0)
			(unlocked yes)
			(layer "F.Fab")
			(hide yes)
			(effects
				(font
					(size 1.016 1.016)
					(thickness 0.1524)
				)
			)
		)
		(duplicate_pad_numbers_are_jumpers no)
		(fp_poly
			(pts
				(arc
					(start 0.3556 0)
					(mid -0.3556 0)
					(end 0.3556 0)
				)
			)
			(stroke
				(width 0)
				(type default)
			)
			(fill no)
			(layer "F.CrtYd")
		)
		(fp_poly
			(pts
				(arc
					(start 0.6096 0)
					(mid -0.6096 0)
					(end 0.6096 0)
				)
			)
			(stroke
				(width 0)
				(type default)
			)
			(fill no)
			(layer "F.Fab")
		)
		(pad "1" smd circle
			(at 0 0)
			(size 0.7112 0.7112)
			(layers "F.Cu" "F.Mask" "F.Paste")
			(net "EXP_PWM_OUT1")
		)
	)
	(footprint ""
		(layer "F.Cu")
		(at 41.402 -175.94834)
		(property "Reference" "SQ14"
			(at 0 0 0)
			(layer "F.SilkS")
			(hide yes)
			(effects
				(font
					(size 1.27 1.27)
				)
			)
		)
		(property "Value" "2N7002A-7-GP"
			(at 0.127 -8.9662 0)
			(unlocked yes)
			(layer "F.Fab")
			(hide yes)
			(effects
				(font
					(size 1.016 1.016)
					(thickness 0.1524)
				)
			)
		)
		(property "Device Type" "SOT23DGS2D4H48"
			(at 0.127 -10.4902 0)
			(unlocked yes)
			(layer "F.Fab")
			(hide yes)
			(effects
				(font
					(size 1.016 1.016)
					(thickness 0.1524)
				)
			)
		)
		(duplicate_pad_numbers_are_jumpers no)
		(fp_line
			(start -1.651 -1.778)
			(end -1.651 1.778)
			(stroke
				(width 0.1524)
				(type default)
			)
			(layer "F.SilkS")
		)
		(fp_line
			(start -1.651 1.778)
			(end 1.651 1.778)
			(stroke
				(width 0.1524)
				(type default)
			)
			(layer "F.SilkS")
		)
		(fp_line
			(start 1.651 -1.778)
			(end -1.651 -1.778)
			(stroke
				(width 0.1524)
				(type default)
			)
			(layer "F.SilkS")
		)
		(fp_line
			(start 1.651 1.778)
			(end 1.651 -1.778)
			(stroke
				(width 0.1524)
				(type default)
			)
			(layer "F.SilkS")
		)
		(fp_poly
			(pts
				(xy -1.778 1.8796) (xy -1.778 -1.8796) (xy 1.778 -1.8796) (xy 1.778 1.8796)
			)
			(stroke
				(width 0)
				(type default)
			)
			(fill no)
			(layer "F.CrtYd")
		)
		(fp_poly
			(pts
				(xy -1.778 1.8796) (xy -1.778 -1.8796) (xy 1.778 -1.8796) (xy 1.778 1.8796)
			)
			(stroke
				(width 0)
				(type default)
			)
			(fill no)
			(layer "F.Fab")
		)
		(pad "D" smd custom
			(at 0 -0.9525)
			(size 0.1905 0.1905)
			(layers "F.Cu" "F.Mask" "F.Paste")
			(net "RST_BTN_R")
			(options
				(clearance outline)
				(anchor circle)
			)
			(primitives
				(gr_poly
					(pts
						(arc
							(start -0.1778 0.5715)
							(mid -0.321484 0.511984)
							(end -0.381 0.3683)
						)
						(arc
							(start -0.381 -0.3683)
							(mid -0.321484 -0.511984)
							(end -0.1778 -0.5715)
						)
						(arc
							(start 0.1778 -0.5715)
							(mid 0.321484 -0.511984)
							(end 0.381 -0.3683)
						)
						(arc
							(start 0.381 0.3683)
							(mid 0.321484 0.511984)
							(end 0.1778 0.5715)
						)
					)
					(width 0)
					(fill yes)
				)
			)
		)
		(pad "G" smd custom
			(at -0.98425 0.9525)
			(size 0.1905 0.1905)
			(layers "F.Cu" "F.Mask" "F.Paste")
			(net "P3V3_STBY_G7")
			(options
				(clearance outline)
				(anchor circle)
			)
			(primitives
				(gr_poly
					(pts
						(arc
							(start -0.1778 0.5715)
							(mid -0.321484 0.511984)
							(end -0.381 0.3683)
						)
						(arc
							(start -0.381 -0.3683)
							(mid -0.321484 -0.511984)
							(end -0.1778 -0.5715)
						)
						(arc
							(start 0.1778 -0.5715)
							(mid 0.321484 -0.511984)
							(end 0.381 -0.3683)
						)
						(arc
							(start 0.381 0.3683)
							(mid 0.321484 0.511984)
							(end 0.1778 0.5715)
						)
					)
					(width 0)
					(fill yes)
				)
			)
		)
		(pad "S" smd custom
			(at 0.98425 0.9525)
			(size 0.1905 0.1905)
			(layers "F.Cu" "F.Mask" "F.Paste")
			(net "GND")
			(options
				(clearance outline)
				(anchor circle)
			)
			(primitives
				(gr_poly
					(pts
						(arc
							(start -0.1778 0.5715)
							(mid -0.321484 0.511984)
							(end -0.381 0.3683)
						)
						(arc
							(start -0.381 -0.3683)
							(mid -0.321484 -0.511984)
							(end -0.1778 -0.5715)
						)
						(arc
							(start 0.1778 -0.5715)
							(mid 0.321484 -0.511984)
							(end 0.381 -0.3683)
						)
						(arc
							(start 0.381 0.3683)
							(mid 0.321484 0.511984)
							(end 0.1778 0.5715)
						)
					)
					(width 0)
					(fill yes)
				)
			)
		)
	)
	(footprint ""
		(layer "F.Cu")
		(at 63.5 -180.086 180)
		(property "Reference" "SR813"
			(at 0 0 180)
			(layer "F.SilkS")
			(hide yes)
			(effects
				(font
					(size 1.27 1.27)
				)
			)
		)
		(property "Value" "4K75R2F-1-GP"
			(at 0.064008 -3.993896 180)
			(unlocked yes)
			(layer "F.Fab")
			(hide yes)
			(effects
				(font
					(size 1.016 1.016)
					(thickness 0.1524)
				)
			)
		)
		(property "Device Type" "R402H16"
			(at 0.064008 -5.517896 180)
			(unlocked yes)
			(layer "F.Fab")
			(hide yes)
			(effects
				(font
					(size 1.016 1.016)
					(thickness 0.1524)
				)
			)
		)
		(duplicate_pad_numbers_are_jumpers no)
		(fp_line
			(start 0.508 -0.9398)
			(end -0.508 -0.9398)
			(stroke
				(width 0.1524)
				(type default)
			)
			(layer "F.SilkS")
		)
		(fp_line
			(start -0.508 -0.9398)
			(end -0.508 0.9398)
			(stroke
				(width 0.1524)
				(type default)
			)
			(layer "F.SilkS")
		)
		(fp_rect
			(start -0.508 0.9398)
			(end 0.508 -0.9398)
			(stroke
				(width 0)
				(type default)
			)
			(fill no)
			(layer "F.CrtYd")
		)
		(fp_rect
			(start -0.508 0.9398)
			(end 0.508 -0.9398)
			(stroke
				(width 0)
				(type default)
			)
			(fill no)
			(layer "F.Fab")
		)
		(pad "1" smd custom
			(at 0 -0.4445 180)
			(size 0.1397 0.1397)
			(layers "F.Cu" "F.Mask" "F.Paste")
			(net "P1V8_E")
			(options
				(clearance outline)
				(anchor circle)
			)
			(primitives
				(gr_poly
					(pts
						(arc
							(start -0.1778 -0.2794)
							(mid -0.249642 -0.249642)
							(end -0.2794 -0.1778)
						)
						(arc
							(start -0.2794 0.1778)
							(mid -0.249642 0.249642)
							(end -0.1778 0.2794)
						)
						(arc
							(start 0.1778 0.2794)
							(mid 0.249642 0.249642)
							(end 0.2794 0.1778)
						)
						(arc
							(start 0.2794 -0.1778)
							(mid 0.249642 -0.249642)
							(end 0.1778 -0.2794)
						)
					)
					(width 0)
					(fill yes)
				)
			)
		)
		(pad "2" smd custom
			(at 0 0.4445 180)
			(size 0.1397 0.1397)
			(layers "F.Cu" "F.Mask" "F.Paste")
			(net "ICE_RESET_N")
			(options
				(clearance outline)
				(anchor circle)
			)
			(primitives
				(gr_poly
					(pts
						(arc
							(start -0.1778 -0.2794)
							(mid -0.249642 -0.249642)
							(end -0.2794 -0.1778)
						)
						(arc
							(start -0.2794 0.1778)
							(mid -0.249642 0.249642)
							(end -0.1778 0.2794)
						)
						(arc
							(start 0.1778 0.2794)
							(mid 0.249642 0.249642)
							(end 0.2794 0.1778)
						)
						(arc
							(start 0.2794 -0.1778)
							(mid 0.249642 -0.249642)
							(end 0.1778 -0.2794)
						)
					)
					(width 0)
					(fill yes)
				)
			)
		)
	)
	(footprint ""
		(layer "F.Cu")
		(at 18.746216 -195.12788 180)
		(property "Reference" "R653"
			(at 0 0 180)
			(layer "F.SilkS")
			(hide yes)
			(effects
				(font
					(size 1.27 1.27)
				)
			)
		)
		(property "Value" "4K7R2F-GP"
			(at 0.064008 -3.993896 180)
			(unlocked yes)
			(layer "F.Fab")
			(hide yes)
			(effects
				(font
					(size 1.016 1.016)
					(thickness 0.1524)
				)
			)
		)
		(property "Device Type" "R402H16"
			(at 0.064008 -5.517896 180)
			(unlocked yes)
			(layer "F.Fab")
			(hide yes)
			(effects
				(font
					(size 1.016 1.016)
					(thickness 0.1524)
				)
			)
		)
		(duplicate_pad_numbers_are_jumpers no)
		(fp_line
			(start 0.508 -0.9398)
			(end -0.508 -0.9398)
			(stroke
				(width 0.1524)
				(type default)
			)
			(layer "F.SilkS")
		)
		(fp_line
			(start -0.508 -0.9398)
			(end -0.508 0.9398)
			(stroke
				(width 0.1524)
				(type default)
			)
			(layer "F.SilkS")
		)
		(fp_rect
			(start -0.508 0.9398)
			(end 0.508 -0.9398)
			(stroke
				(width 0)
				(type default)
			)
			(fill no)
			(layer "F.CrtYd")
		)
		(fp_rect
			(start -0.508 0.9398)
			(end 0.508 -0.9398)
			(stroke
				(width 0)
				(type default)
			)
			(fill no)
			(layer "F.Fab")
		)
		(pad "1" smd custom
			(at 0 -0.4445 180)
			(size 0.1397 0.1397)
			(layers "F.Cu" "F.Mask" "F.Paste")
			(net "P3V3_STBY")
			(options
				(clearance outline)
				(anchor circle)
			)
			(primitives
				(gr_poly
					(pts
						(arc
							(start -0.1778 -0.2794)
							(mid -0.249642 -0.249642)
							(end -0.2794 -0.1778)
						)
						(arc
							(start -0.2794 0.1778)
							(mid -0.249642 0.249642)
							(end -0.1778 0.2794)
						)
						(arc
							(start 0.1778 0.2794)
							(mid 0.249642 0.249642)
							(end 0.2794 0.1778)
						)
						(arc
							(start 0.2794 -0.1778)
							(mid 0.249642 -0.249642)
							(end 0.1778 -0.2794)
						)
					)
					(width 0)
					(fill yes)
				)
			)
		)
		(pad "2" smd custom
			(at 0 0.4445 180)
			(size 0.1397 0.1397)
			(layers "F.Cu" "F.Mask" "F.Paste")
			(net "IO_EXP_HDD_PRE_A1")
			(options
				(clearance outline)
				(anchor circle)
			)
			(primitives
				(gr_poly
					(pts
						(arc
							(start -0.1778 -0.2794)
							(mid -0.249642 -0.249642)
							(end -0.2794 -0.1778)
						)
						(arc
							(start -0.2794 0.1778)
							(mid -0.249642 0.249642)
							(end -0.1778 0.2794)
						)
						(arc
							(start 0.1778 0.2794)
							(mid 0.249642 0.249642)
							(end 0.2794 0.1778)
						)
						(arc
							(start 0.2794 -0.1778)
							(mid 0.249642 -0.249642)
							(end 0.1778 -0.2794)
						)
					)
					(width 0)
					(fill yes)
				)
			)
		)
	)
	(footprint ""
		(layer "F.Cu")
		(at 250.259596 -54.502812 -90)
		(property "Reference" "SR723"
			(at 0 0 270)
			(layer "F.SilkS")
			(hide yes)
			(effects
				(font
					(size 1.27 1.27)
				)
			)
		)
		(property "Value" "0R2J-2-GP"
			(at 0.064008 -3.993896 270)
			(unlocked yes)
			(layer "F.Fab")
			(hide yes)
			(effects
				(font
					(size 1.016 1.016)
					(thickness 0.1524)
				)
			)
		)
		(property "Device Type" "R402H16"
			(at 0.064008 -5.517896 270)
			(unlocked yes)
			(layer "F.Fab")
			(hide yes)
			(effects
				(font
					(size 1.016 1.016)
					(thickness 0.1524)
				)
			)
		)
		(duplicate_pad_numbers_are_jumpers no)
		(fp_line
			(start -0.508 -0.9398)
			(end -0.508 0.9398)
			(stroke
				(width 0.1524)
				(type default)
			)
			(layer "F.SilkS")
		)
		(fp_line
			(start 0.508 -0.9398)
			(end -0.508 -0.9398)
			(stroke
				(width 0.1524)
				(type default)
			)
			(layer "F.SilkS")
		)
		(fp_rect
			(start -0.508 0.9398)
			(end 0.508 -0.9398)
			(stroke
				(width 0)
				(type default)
			)
			(fill no)
			(layer "F.CrtYd")
		)
		(fp_rect
			(start -0.508 0.9398)
			(end 0.508 -0.9398)
			(stroke
				(width 0)
				(type default)
			)
			(fill no)
			(layer "F.Fab")
		)
		(pad "1" smd custom
			(at 0 -0.4445 270)
			(size 0.1397 0.1397)
			(layers "F.Cu" "F.Mask" "F.Paste")
			(net "IOC_EEPROM_SDA")
			(options
				(clearance outline)
				(anchor circle)
			)
			(primitives
				(gr_poly
					(pts
						(arc
							(start -0.1778 -0.2794)
							(mid -0.249642 -0.249642)
							(end -0.2794 -0.1778)
						)
						(arc
							(start -0.2794 0.1778)
							(mid -0.249642 0.249642)
							(end -0.1778 0.2794)
						)
						(arc
							(start 0.1778 0.2794)
							(mid 0.249642 0.249642)
							(end 0.2794 0.1778)
						)
						(arc
							(start 0.2794 -0.1778)
							(mid 0.249642 -0.249642)
							(end 0.1778 -0.2794)
						)
					)
					(width 0)
					(fill yes)
				)
			)
		)
		(pad "2" smd custom
			(at 0 0.4445 270)
			(size 0.1397 0.1397)
			(layers "F.Cu" "F.Mask" "F.Paste")
			(net "SBL_SDA")
			(options
				(clearance outline)
				(anchor circle)
			)
			(primitives
				(gr_poly
					(pts
						(arc
							(start -0.1778 -0.2794)
							(mid -0.249642 -0.249642)
							(end -0.2794 -0.1778)
						)
						(arc
							(start -0.2794 0.1778)
							(mid -0.249642 0.249642)
							(end -0.1778 0.2794)
						)
						(arc
							(start 0.1778 0.2794)
							(mid 0.249642 0.249642)
							(end 0.2794 0.1778)
						)
						(arc
							(start 0.2794 -0.1778)
							(mid 0.249642 -0.249642)
							(end 0.1778 -0.2794)
						)
					)
					(width 0)
					(fill yes)
				)
			)
		)
	)
	(footprint ""
		(layer "F.Cu")
		(at 88.138 -242.443 180)
		(property "Reference" "SR953"
			(at 0 0 180)
			(layer "F.SilkS")
			(hide yes)
			(effects
				(font
					(size 1.27 1.27)
				)
			)
		)
		(property "Value" "4K7R2F-GP"
			(at 0.064008 -3.993896 180)
			(unlocked yes)
			(layer "F.Fab")
			(hide yes)
			(effects
				(font
					(size 1.016 1.016)
					(thickness 0.1524)
				)
			)
		)
		(property "Device Type" "R402H16"
			(at 0.064008 -5.517896 180)
			(unlocked yes)
			(layer "F.Fab")
			(hide yes)
			(effects
				(font
					(size 1.016 1.016)
					(thickness 0.1524)
				)
			)
		)
		(duplicate_pad_numbers_are_jumpers no)
		(fp_line
			(start 0.508 -0.9398)
			(end -0.508 -0.9398)
			(stroke
				(width 0.1524)
				(type default)
			)
			(layer "F.SilkS")
		)
		(fp_line
			(start -0.508 -0.9398)
			(end -0.508 0.9398)
			(stroke
				(width 0.1524)
				(type default)
			)
			(layer "F.SilkS")
		)
		(fp_rect
			(start -0.508 0.9398)
			(end 0.508 -0.9398)
			(stroke
				(width 0)
				(type default)
			)
			(fill no)
			(layer "F.CrtYd")
		)
		(fp_rect
			(start -0.508 0.9398)
			(end 0.508 -0.9398)
			(stroke
				(width 0)
				(type default)
			)
			(fill no)
			(layer "F.Fab")
		)
		(pad "1" smd custom
			(at 0 -0.4445 180)
			(size 0.1397 0.1397)
			(layers "F.Cu" "F.Mask" "F.Paste")
			(net "SAS_FAULT_LED12")
			(options
				(clearance outline)
				(anchor circle)
			)
			(primitives
				(gr_poly
					(pts
						(arc
							(start -0.1778 -0.2794)
							(mid -0.249642 -0.249642)
							(end -0.2794 -0.1778)
						)
						(arc
							(start -0.2794 0.1778)
							(mid -0.249642 0.249642)
							(end -0.1778 0.2794)
						)
						(arc
							(start 0.1778 0.2794)
							(mid 0.249642 0.249642)
							(end 0.2794 0.1778)
						)
						(arc
							(start 0.2794 -0.1778)
							(mid 0.249642 -0.249642)
							(end 0.1778 -0.2794)
						)
					)
					(width 0)
					(fill yes)
				)
			)
		)
		(pad "2" smd custom
			(at 0 0.4445 180)
			(size 0.1397 0.1397)
			(layers "F.Cu" "F.Mask" "F.Paste")
			(net "P3V3_STBY")
			(options
				(clearance outline)
				(anchor circle)
			)
			(primitives
				(gr_poly
					(pts
						(arc
							(start -0.1778 -0.2794)
							(mid -0.249642 -0.249642)
							(end -0.2794 -0.1778)
						)
						(arc
							(start -0.2794 0.1778)
							(mid -0.249642 0.249642)
							(end -0.1778 0.2794)
						)
						(arc
							(start 0.1778 0.2794)
							(mid 0.249642 0.249642)
							(end 0.2794 0.1778)
						)
						(arc
							(start 0.2794 -0.1778)
							(mid 0.249642 -0.249642)
							(end 0.1778 -0.2794)
						)
					)
					(width 0)
					(fill yes)
				)
			)
		)
	)
	(footprint ""
		(layer "F.Cu")
		(at 324.485 -118.491 180)
		(property "Reference" "PC23"
			(at 0 0 180)
			(layer "F.SilkS")
			(hide yes)
			(effects
				(font
					(size 1.27 1.27)
				)
			)
		)
		(property "Value" "SC22U25V5MX-GP"
			(at -0.0762 -6.1214 180)
			(unlocked yes)
			(layer "F.Fab")
			(hide yes)
			(effects
				(font
					(size 1.016 1.016)
					(thickness 0.1524)
				)
			)
		)
		(property "Device Type" "C805H58"
			(at -0.0762 -8.1534 180)
			(unlocked yes)
			(layer "F.Fab")
			(hide yes)
			(effects
				(font
					(size 1.016 1.016)
					(thickness 0.1524)
				)
			)
		)
		(duplicate_pad_numbers_are_jumpers no)
		(fp_line
			(start 0.635 0)
			(end -0.635 0)
			(stroke
				(width 0.508)
				(type default)
			)
			(layer "F.SilkS")
		)
		(fp_rect
			(start -0.9652 1.778)
			(end 0.9652 -1.778)
			(stroke
				(width 0)
				(type default)
			)
			(fill no)
			(layer "F.CrtYd")
		)
		(fp_poly
			(pts
				(xy -0.9652 -1.778) (xy 0.9652 -1.778) (xy 0.9652 1.778) (xy -0.9652 1.778)
			)
			(stroke
				(width 0)
				(type default)
			)
			(fill no)
			(layer "F.Fab")
		)
		(pad "1" smd rect
			(at 0 -0.9652 180)
			(size 1.397 1.143)
			(layers "F.Cu" "F.Mask" "F.Paste")
			(net "P3V3_STBY_VIN")
		)
		(pad "2" smd rect
			(at 0 0.9652 180)
			(size 1.397 1.143)
			(layers "F.Cu" "F.Mask" "F.Paste")
			(net "GND")
		)
	)
)
